(kicad_pcb
	(version 20260206)
	(generator "pcbnew")
	(generator_version "10.0")
	(general
		(thickness 1.6)
		(legacy_teardrops no)
	)
	(paper "A4")
	(title_block
		(title "04192023_DAF0TMB3IC0_F0TG_MB_C_brd_V02_OCP.brd")
		(comment 1 "Grand Teton / footprints 4498-4503 of 8354")
	)
	(layers
		(0 "F.Cu" signal "TOP")
		(4 "In1.Cu" signal "GND")
		(6 "In2.Cu" signal "IN1")
		(8 "In3.Cu" signal "GND1")
		(10 "In4.Cu" signal "IN2")
		(12 "In5.Cu" signal "GND2")
		(14 "In6.Cu" signal "IN3")
		(16 "In7.Cu" signal "GND3")
		(18 "In8.Cu" signal "VCC")
		(20 "In9.Cu" signal "VCC1")
		(22 "In10.Cu" signal "GND4")
		(24 "In11.Cu" signal "IN4")
		(26 "In12.Cu" signal "GND5")
		(28 "In13.Cu" signal "IN5")
		(30 "In14.Cu" signal "GND6")
		(32 "In15.Cu" signal "IN6")
		(34 "In16.Cu" signal "GND7")
		(2 "B.Cu" signal "BOTTOM")
		(9 "F.Adhes" user "F.Adhesive")
		(11 "B.Adhes" user "B.Adhesive")
		(13 "F.Paste" user "Package Geometry/Pastemask Top")
		(15 "B.Paste" user "Package Geometry/Pastemask Bottom")
		(5 "F.SilkS" user "Ref Des/Silkscreen Top")
		(7 "B.SilkS" user "Ref Des/Silkscreen Bottom")
		(1 "F.Mask" user "Board Geometry/Soldermask Top")
		(3 "B.Mask" user "Board Geometry/Soldermask Bottom")
		(17 "Dwgs.User" user "User.Drawings")
		(19 "Cmts.User" user "User.Comments")
		(21 "Eco1.User" user "User.Eco1")
		(23 "Eco2.User" user "User.Eco2")
		(25 "Edge.Cuts" user "Board Geometry/Outline")
		(27 "Margin" user)
		(31 "F.CrtYd" user "Package Geometry/Place Bound Top")
		(29 "B.CrtYd" user "Package Geometry/Place Bound Bottom")
		(35 "F.Fab" user "Ref Des/Assembly Top")
		(33 "B.Fab" user "Ref Des/Assembly Bottom")
	)
	(footprint ""
		(layer "F.Cu")
		(at 503.645424 -457.3397 90)
		(property "Reference" "X9008"
			(at -2.017268 1.17475 0)
			(unlocked yes)
			(layer "F.SilkS")
			(effects
				(font
					(size 0.7874 0.5842)
					(thickness 0.1524)
				)
				(justify left)
			)
		)
		(property "Value" ""
			(at 0 0 90)
			(layer "F.Fab")
			(effects
				(font
					(size 1.27 1.27)
				)
			)
		)
		(property "User Part Number" "N_A"
			(at 1.30175 1.27 180)
			(unlocked yes)
			(layer "Cmts.User")
			(hide yes)
			(effects
				(font
					(size 0.635 0.4064)
					(thickness 0.1524)
				)
			)
		)
		(property "Device Type" "TP_TDR_4P_FTS_TH-TP_TDR_4P_DIP,EMPTY,TP15"
			(at 1.30175 1.27 180)
			(unlocked yes)
			(layer "F.Fab")
			(hide yes)
			(effects
				(font
					(size 0.635 0.4064)
					(thickness 0.1524)
				)
			)
		)
		(duplicate_pad_numbers_are_jumpers no)
		(fp_line
			(start 2.54 -1.27)
			(end 0 -1.27)
			(stroke
				(width 0.1524)
				(type default)
			)
			(layer "F.SilkS")
		)
		(fp_line
			(start 0 -1.27)
			(end 0 -0.635)
			(stroke
				(width 0.1524)
				(type default)
			)
			(layer "F.SilkS")
		)
		(fp_line
			(start 2.54 -1.1303)
			(end 2.54 -1.27)
			(stroke
				(width 0.1524)
				(type default)
			)
			(layer "F.SilkS")
		)
		(fp_line
			(start 0 0.635)
			(end 0 1.905)
			(stroke
				(width 0.1524)
				(type default)
			)
			(layer "F.SilkS")
		)
		(fp_line
			(start 2.54 1.4097)
			(end 2.54 1.1303)
			(stroke
				(width 0.1524)
				(type default)
			)
			(layer "F.SilkS")
		)
		(fp_line
			(start 0 3.175)
			(end 0 3.81)
			(stroke
				(width 0.1524)
				(type default)
			)
			(layer "F.SilkS")
		)
		(fp_line
			(start 2.54 3.81)
			(end 2.54 3.6703)
			(stroke
				(width 0.1524)
				(type default)
			)
			(layer "F.SilkS")
		)
		(fp_line
			(start 0 3.81)
			(end 2.54 3.81)
			(stroke
				(width 0.1524)
				(type default)
			)
			(layer "F.SilkS")
		)
		(fp_poly
			(pts
				(xy -2.285746 -0.762) (xy -0.761746 0) (xy -2.285746 0.762)
			)
			(stroke
				(width 0)
				(type default)
			)
			(fill yes)
			(layer "F.SilkS")
		)
		(fp_line
			(start 2.54 -1.27)
			(end 0 -1.27)
			(stroke
				(width 0.1)
				(type default)
			)
			(layer "F.Fab")
		)
		(fp_line
			(start 0 -1.27)
			(end 0 3.81)
			(stroke
				(width 0.1)
				(type default)
			)
			(layer "F.Fab")
		)
		(fp_line
			(start 2.54 3.81)
			(end 2.54 -1.27)
			(stroke
				(width 0.1)
				(type default)
			)
			(layer "F.Fab")
		)
		(fp_line
			(start 0 3.81)
			(end 2.54 3.81)
			(stroke
				(width 0.1)
				(type default)
			)
			(layer "F.Fab")
		)
		(fp_poly
			(pts
				(xy -0.761746 0) (xy -2.285746 -0.762) (xy -2.285746 0.762)
			)
			(stroke
				(width 0)
				(type default)
			)
			(fill yes)
			(layer "F.Fab")
		)
		(pad "1" thru_hole circle
			(at 0 0 90)
			(size 1.0033 1.0033)
			(drill 0.249936)
			(layers "*.Cu" "*.Mask")
			(remove_unused_layers no)
			(net "TDR_DIFF_85_NECK_IN1_DN")
			(clearance 0.10795)
			(thermal_gap 0.10795)
			(padstack
				(mode front_inner_back)
				(layer "Inner"
					(shape circle)
					(size 0.8001 0.8001)
					(clearance 0.1524)
				)
				(layer "B.Cu"
					(shape circle)
					(size 1.0033 1.0033)
					(clearance 0.10795)
				)
			)
		)
		(pad "2" thru_hole circle
			(at 2.54 0 90)
			(size 1.9939 1.9939)
			(drill 0.249936)
			(layers "*.Cu" "*.Mask")
			(remove_unused_layers no)
			(net "T1_GND")
			(clearance 0.10795)
			(thermal_gap 0.10795)
			(padstack
				(mode front_inner_back)
				(layer "Inner"
					(shape circle)
					(size 0.8001 0.8001)
					(clearance 0.1524)
				)
				(layer "B.Cu"
					(shape circle)
					(size 1.9939 1.9939)
					(clearance 0.10795)
				)
			)
		)
		(pad "3" thru_hole circle
			(at 2.54 2.54 90)
			(size 1.9939 1.9939)
			(drill 0.249936)
			(layers "*.Cu" "*.Mask")
			(remove_unused_layers no)
			(net "T1_GND")
			(clearance 0.10795)
			(thermal_gap 0.10795)
			(padstack
				(mode front_inner_back)
				(layer "Inner"
					(shape circle)
					(size 0.8001 0.8001)
					(clearance 0.1524)
				)
				(layer "B.Cu"
					(shape circle)
					(size 1.9939 1.9939)
					(clearance 0.10795)
				)
			)
		)
		(pad "4" thru_hole circle
			(at 0 2.54 90)
			(size 1.0033 1.0033)
			(drill 0.249936)
			(layers "*.Cu" "*.Mask")
			(remove_unused_layers no)
			(net "TDR_DIFF_85_NECK_IN1_DP")
			(clearance 0.10795)
			(thermal_gap 0.10795)
			(padstack
				(mode front_inner_back)
				(layer "Inner"
					(shape circle)
					(size 0.8001 0.8001)
					(clearance 0.1524)
				)
				(layer "B.Cu"
					(shape circle)
					(size 1.0033 1.0033)
					(clearance 0.10795)
				)
			)
		)
	)
	(footprint ""
		(layer "F.Cu")
		(at 62.00775 -168.843452 90)
		(property "Reference" "PC128_6"
			(at 0 0 90)
			(layer "F.SilkS")
			(hide yes)
			(effects
				(font
					(size 1.27 1.27)
				)
			)
		)
		(property "Value" ""
			(at 0 0 90)
			(layer "F.Fab")
			(effects
				(font
					(size 1.27 1.27)
				)
			)
		)
		(duplicate_pad_numbers_are_jumpers no)
		(fp_line
			(start 0.7874 -0.4064)
			(end 0.7874 0.4064)
			(stroke
				(width 0.1524)
				(type default)
			)
			(layer "F.SilkS")
		)
		(fp_line
			(start -0.7874 -0.4064)
			(end 0.7874 -0.4064)
			(stroke
				(width 0.1524)
				(type default)
			)
			(layer "F.SilkS")
		)
		(fp_line
			(start 0.7874 0.4064)
			(end -0.7874 0.4064)
			(stroke
				(width 0.1524)
				(type default)
			)
			(layer "F.SilkS")
		)
		(fp_line
			(start -0.7874 0.4064)
			(end -0.7874 -0.4064)
			(stroke
				(width 0.1524)
				(type default)
			)
			(layer "F.SilkS")
		)
		(fp_line
			(start -0.12065 -0.305054)
			(end -0.12065 -0.2794)
			(stroke
				(width 0.1)
				(type default)
			)
			(layer "F.Fab")
		)
		(fp_line
			(start -0.67945 -0.305054)
			(end -0.12065 -0.305054)
			(stroke
				(width 0.1)
				(type default)
			)
			(layer "F.Fab")
		)
		(fp_line
			(start 0.67945 -0.3048)
			(end 0.67945 0.3048)
			(stroke
				(width 0.1)
				(type default)
			)
			(layer "F.Fab")
		)
		(fp_line
			(start 0.12065 -0.3048)
			(end 0.67945 -0.3048)
			(stroke
				(width 0.1)
				(type default)
			)
			(layer "F.Fab")
		)
		(fp_line
			(start 0.12065 -0.2794)
			(end 0.12065 -0.3048)
			(stroke
				(width 0.1)
				(type default)
			)
			(layer "F.Fab")
		)
		(fp_line
			(start -0.12065 -0.2794)
			(end 0.12065 -0.2794)
			(stroke
				(width 0.1)
				(type default)
			)
			(layer "F.Fab")
		)
		(fp_line
			(start 0.120396 0.2794)
			(end -0.12065 0.2794)
			(stroke
				(width 0.1)
				(type default)
			)
			(layer "F.Fab")
		)
		(fp_line
			(start -0.12065 0.2794)
			(end -0.12065 0.3048)
			(stroke
				(width 0.1)
				(type default)
			)
			(layer "F.Fab")
		)
		(fp_line
			(start 0.67945 0.3048)
			(end 0.120396 0.3048)
			(stroke
				(width 0.1)
				(type default)
			)
			(layer "F.Fab")
		)
		(fp_line
			(start 0.120396 0.3048)
			(end 0.120396 0.2794)
			(stroke
				(width 0.1)
				(type default)
			)
			(layer "F.Fab")
		)
		(fp_line
			(start -0.12065 0.3048)
			(end -0.67945 0.3048)
			(stroke
				(width 0.1)
				(type default)
			)
			(layer "F.Fab")
		)
		(fp_line
			(start -0.67945 0.3048)
			(end -0.67945 -0.305054)
			(stroke
				(width 0.1)
				(type default)
			)
			(layer "F.Fab")
		)
		(pad "1" smd circle
			(at -0.40005 0 90)
			(size 0 0)
			(layers "F.Cu" "F.Mask" "F.Paste")
			(net "SW_P12V_AUX_PVDDCR_CPU0_P1_FLT")
		)
		(pad "2" smd circle
			(at 0.40005 0 90)
			(size 0 0)
			(layers "F.Cu" "F.Mask" "F.Paste")
			(net "GND")
		)
	)
	(footprint ""
		(layer "F.Cu")
		(at 391.616692 -378.95403 -90)
		(property "Reference" "C875"
			(at 0 0 270)
			(layer "F.SilkS")
			(hide yes)
			(effects
				(font
					(size 1.27 1.27)
				)
			)
		)
		(property "Value" ""
			(at 0 0 270)
			(layer "F.Fab")
			(effects
				(font
					(size 1.27 1.27)
				)
			)
		)
		(duplicate_pad_numbers_are_jumpers no)
		(fp_line
			(start -0.299974 0.150114)
			(end -0.299974 -0.150114)
			(stroke
				(width 0.1)
				(type default)
			)
			(layer "F.Fab")
		)
		(fp_line
			(start 0.299974 0.150114)
			(end -0.299974 0.150114)
			(stroke
				(width 0.1)
				(type default)
			)
			(layer "F.Fab")
		)
		(fp_line
			(start -0.299974 -0.150114)
			(end 0.299974 -0.150114)
			(stroke
				(width 0.1)
				(type default)
			)
			(layer "F.Fab")
		)
		(fp_line
			(start 0.299974 -0.150114)
			(end 0.299974 0.150114)
			(stroke
				(width 0.1)
				(type default)
			)
			(layer "F.Fab")
		)
		(pad "1" smd rect
			(at -0.2667 0 270)
			(size 0.3048 0.381)
			(layers "F.Cu" "F.Mask" "F.Paste")
			(net "P5E_CPU0_P3_TX_C_DP<13>")
		)
		(pad "2" smd rect
			(at 0.2667 0 270)
			(size 0.3048 0.381)
			(layers "F.Cu" "F.Mask" "F.Paste")
			(net "P5E_CPU0_P3_TX_DP<13>")
		)
	)
	(footprint ""
		(layer "F.Cu")
		(at 167.132 -115.280948 180)
		(property "Reference" "R64"
			(at 0 0 180)
			(layer "F.SilkS")
			(hide yes)
			(effects
				(font
					(size 1.27 1.27)
				)
			)
		)
		(property "Value" ""
			(at 0 0 180)
			(layer "F.Fab")
			(effects
				(font
					(size 1.27 1.27)
				)
			)
		)
		(duplicate_pad_numbers_are_jumpers no)
		(fp_line
			(start 0.7874 0.4064)
			(end -0.7874 0.4064)
			(stroke
				(width 0.1524)
				(type default)
			)
			(layer "F.SilkS")
		)
		(fp_line
			(start 0.7874 -0.4064)
			(end 0.7874 0.4064)
			(stroke
				(width 0.1524)
				(type default)
			)
			(layer "F.SilkS")
		)
		(fp_line
			(start -0.7874 0.4064)
			(end -0.7874 -0.4064)
			(stroke
				(width 0.1524)
				(type default)
			)
			(layer "F.SilkS")
		)
		(fp_line
			(start -0.7874 -0.4064)
			(end 0.7874 -0.4064)
			(stroke
				(width 0.1524)
				(type default)
			)
			(layer "F.SilkS")
		)
		(fp_line
			(start 0.67945 0.3048)
			(end 0.120396 0.3048)
			(stroke
				(width 0.1)
				(type default)
			)
			(layer "F.Fab")
		)
		(fp_line
			(start 0.67945 -0.3048)
			(end 0.67945 0.3048)
			(stroke
				(width 0.1)
				(type default)
			)
			(layer "F.Fab")
		)
		(fp_line
			(start 0.12065 -0.2794)
			(end 0.12065 -0.3048)
			(stroke
				(width 0.1)
				(type default)
			)
			(layer "F.Fab")
		)
		(fp_line
			(start 0.12065 -0.3048)
			(end 0.67945 -0.3048)
			(stroke
				(width 0.1)
				(type default)
			)
			(layer "F.Fab")
		)
		(fp_line
			(start 0.120396 0.3048)
			(end 0.120396 0.2794)
			(stroke
				(width 0.1)
				(type default)
			)
			(layer "F.Fab")
		)
		(fp_line
			(start 0.120396 0.2794)
			(end -0.12065 0.2794)
			(stroke
				(width 0.1)
				(type default)
			)
			(layer "F.Fab")
		)
		(fp_line
			(start -0.12065 0.3048)
			(end -0.67945 0.3048)
			(stroke
				(width 0.1)
				(type default)
			)
			(layer "F.Fab")
		)
		(fp_line
			(start -0.12065 0.2794)
			(end -0.12065 0.3048)
			(stroke
				(width 0.1)
				(type default)
			)
			(layer "F.Fab")
		)
		(fp_line
			(start -0.12065 -0.2794)
			(end 0.12065 -0.2794)
			(stroke
				(width 0.1)
				(type default)
			)
			(layer "F.Fab")
		)
		(fp_line
			(start -0.12065 -0.305054)
			(end -0.12065 -0.2794)
			(stroke
				(width 0.1)
				(type default)
			)
			(layer "F.Fab")
		)
		(fp_line
			(start -0.67945 0.3048)
			(end -0.67945 -0.305054)
			(stroke
				(width 0.1)
				(type default)
			)
			(layer "F.Fab")
		)
		(fp_line
			(start -0.67945 -0.305054)
			(end -0.12065 -0.305054)
			(stroke
				(width 0.1)
				(type default)
			)
			(layer "F.Fab")
		)
		(pad "1" smd circle
			(at -0.40005 0 180)
			(size 0 0)
			(layers "F.Cu" "F.Mask" "F.Paste")
			(net "SCM_SYS_PWRBTN_N")
		)
		(pad "2" smd circle
			(at 0.40005 0 180)
			(size 0 0)
			(layers "F.Cu" "F.Mask" "F.Paste")
			(net "P3V3_AUX")
		)
	)
	(footprint ""
		(layer "F.Cu")
		(at 171.196 -114.264948 180)
		(property "Reference" "R160"
			(at 0 0 180)
			(layer "F.SilkS")
			(hide yes)
			(effects
				(font
					(size 1.27 1.27)
				)
			)
		)
		(property "Value" ""
			(at 0 0 180)
			(layer "F.Fab")
			(effects
				(font
					(size 1.27 1.27)
				)
			)
		)
		(duplicate_pad_numbers_are_jumpers no)
		(fp_line
			(start 0.7874 0.4064)
			(end -0.7874 0.4064)
			(stroke
				(width 0.1524)
				(type default)
			)
			(layer "F.SilkS")
		)
		(fp_line
			(start 0.7874 -0.4064)
			(end 0.7874 0.4064)
			(stroke
				(width 0.1524)
				(type default)
			)
			(layer "F.SilkS")
		)
		(fp_line
			(start -0.7874 0.4064)
			(end -0.7874 -0.4064)
			(stroke
				(width 0.1524)
				(type default)
			)
			(layer "F.SilkS")
		)
		(fp_line
			(start -0.7874 -0.4064)
			(end 0.7874 -0.4064)
			(stroke
				(width 0.1524)
				(type default)
			)
			(layer "F.SilkS")
		)
		(fp_line
			(start 0.67945 0.3048)
			(end 0.120396 0.3048)
			(stroke
				(width 0.1)
				(type default)
			)
			(layer "F.Fab")
		)
		(fp_line
			(start 0.67945 -0.3048)
			(end 0.67945 0.3048)
			(stroke
				(width 0.1)
				(type default)
			)
			(layer "F.Fab")
		)
		(fp_line
			(start 0.12065 -0.2794)
			(end 0.12065 -0.3048)
			(stroke
				(width 0.1)
				(type default)
			)
			(layer "F.Fab")
		)
		(fp_line
			(start 0.12065 -0.3048)
			(end 0.67945 -0.3048)
			(stroke
				(width 0.1)
				(type default)
			)
			(layer "F.Fab")
		)
		(fp_line
			(start 0.120396 0.3048)
			(end 0.120396 0.2794)
			(stroke
				(width 0.1)
				(type default)
			)
			(layer "F.Fab")
		)
		(fp_line
			(start 0.120396 0.2794)
			(end -0.12065 0.2794)
			(stroke
				(width 0.1)
				(type default)
			)
			(layer "F.Fab")
		)
		(fp_line
			(start -0.12065 0.3048)
			(end -0.67945 0.3048)
			(stroke
				(width 0.1)
				(type default)
			)
			(layer "F.Fab")
		)
		(fp_line
			(start -0.12065 0.2794)
			(end -0.12065 0.3048)
			(stroke
				(width 0.1)
				(type default)
			)
			(layer "F.Fab")
		)
		(fp_line
			(start -0.12065 -0.2794)
			(end 0.12065 -0.2794)
			(stroke
				(width 0.1)
				(type default)
			)
			(layer "F.Fab")
		)
		(fp_line
			(start -0.12065 -0.305054)
			(end -0.12065 -0.2794)
			(stroke
				(width 0.1)
				(type default)
			)
			(layer "F.Fab")
		)
		(fp_line
			(start -0.67945 0.3048)
			(end -0.67945 -0.305054)
			(stroke
				(width 0.1)
				(type default)
			)
			(layer "F.Fab")
		)
		(fp_line
			(start -0.67945 -0.305054)
			(end -0.12065 -0.305054)
			(stroke
				(width 0.1)
				(type default)
			)
			(layer "F.Fab")
		)
		(pad "1" smd circle
			(at -0.40005 0 180)
			(size 0 0)
			(layers "F.Cu" "F.Mask" "F.Paste")
			(net "JTAG_SCM_TRST_R_N")
		)
		(pad "2" smd circle
			(at 0.40005 0 180)
			(size 0 0)
			(layers "F.Cu" "F.Mask" "F.Paste")
			(net "JTAG_SCM_TRST_N")
		)
	)
	(footprint ""
		(layer "F.Cu")
		(at 323.637148 -40.144954)
		(property "Reference" "R3687"
			(at 0 0 0)
			(layer "F.SilkS")
			(hide yes)
			(effects
				(font
					(size 1.27 1.27)
				)
			)
		)
		(property "Value" ""
			(at 0 0 0)
			(layer "F.Fab")
			(effects
				(font
					(size 1.27 1.27)
				)
			)
		)
		(duplicate_pad_numbers_are_jumpers no)
		(fp_line
			(start -0.7874 -0.4064)
			(end 0.7874 -0.4064)
			(stroke
				(width 0.1524)
				(type default)
			)
			(layer "F.SilkS")
		)
		(fp_line
			(start -0.7874 0.4064)
			(end -0.7874 -0.4064)
			(stroke
				(width 0.1524)
				(type default)
			)
			(layer "F.SilkS")
		)
		(fp_line
			(start 0.7874 -0.4064)
			(end 0.7874 0.4064)
			(stroke
				(width 0.1524)
				(type default)
			)
			(layer "F.SilkS")
		)
		(fp_line
			(start 0.7874 0.4064)
			(end -0.7874 0.4064)
			(stroke
				(width 0.1524)
				(type default)
			)
			(layer "F.SilkS")
		)
		(fp_line
			(start -0.67945 -0.305054)
			(end -0.12065 -0.305054)
			(stroke
				(width 0.1)
				(type default)
			)
			(layer "F.Fab")
		)
		(fp_line
			(start -0.67945 0.3048)
			(end -0.67945 -0.305054)
			(stroke
				(width 0.1)
				(type default)
			)
			(layer "F.Fab")
		)
		(fp_line
			(start -0.12065 -0.305054)
			(end -0.12065 -0.2794)
			(stroke
				(width 0.1)
				(type default)
			)
			(layer "F.Fab")
		)
		(fp_line
			(start -0.12065 -0.2794)
			(end 0.12065 -0.2794)
			(stroke
				(width 0.1)
				(type default)
			)
			(layer "F.Fab")
		)
		(fp_line
			(start -0.12065 0.2794)
			(end -0.12065 0.3048)
			(stroke
				(width 0.1)
				(type default)
			)
			(layer "F.Fab")
		)
		(fp_line
			(start -0.12065 0.3048)
			(end -0.67945 0.3048)
			(stroke
				(width 0.1)
				(type default)
			)
			(layer "F.Fab")
		)
		(fp_line
			(start 0.120396 0.2794)
			(end -0.12065 0.2794)
			(stroke
				(width 0.1)
				(type default)
			)
			(layer "F.Fab")
		)
		(fp_line
			(start 0.120396 0.3048)
			(end 0.120396 0.2794)
			(stroke
				(width 0.1)
				(type default)
			)
			(layer "F.Fab")
		)
		(fp_line
			(start 0.12065 -0.3048)
			(end 0.67945 -0.3048)
			(stroke
				(width 0.1)
				(type default)
			)
			(layer "F.Fab")
		)
		(fp_line
			(start 0.12065 -0.2794)
			(end 0.12065 -0.3048)
			(stroke
				(width 0.1)
				(type default)
			)
			(layer "F.Fab")
		)
		(fp_line
			(start 0.67945 -0.3048)
			(end 0.67945 0.3048)
			(stroke
				(width 0.1)
				(type default)
			)
			(layer "F.Fab")
		)
		(fp_line
			(start 0.67945 0.3048)
			(end 0.120396 0.3048)
			(stroke
				(width 0.1)
				(type default)
			)
			(layer "F.Fab")
		)
		(pad "1" smd rect
			(at -0.40005 0 180)
			(size 0.4572 0.508)
			(layers "F.Cu" "F.Mask" "F.Paste")
			(net "P1V581_PDB_ADC")
		)
		(pad "2" smd rect
			(at 0.40005 0 180)
			(size 0.4572 0.508)
			(layers "F.Cu" "F.Mask" "F.Paste")
			(net "P3V3_PDB_AUX_ADC_MAM")
		)
	)
)
